(kicad_pcb
	(version 20241229)
	(generator "pcbnew")
	(generator_version "9.0")
	(general
		(thickness 1.6)
		(legacy_teardrops no)
	)
	(paper "A4")
	(title_block
		(title "GMSL Deserializer")
		(date "2025-10-09")
		(rev "1.0.4")
		(company "Antmicro Ltd")
		(comment 1 "www.antmicro.com")
		(comment 9 "footprints 129-133 of 235")
	)
	(layers
		(0 "F.Cu" signal)
		(4 "In1.Cu" power)
		(6 "In2.Cu" power)
		(2 "B.Cu" signal)
		(9 "F.Adhes" user "F.Adhesive")
		(11 "B.Adhes" user "B.Adhesive")
		(13 "F.Paste" user)
		(15 "B.Paste" user)
		(5 "F.SilkS" user "F.Silkscreen")
		(7 "B.SilkS" user "B.Silkscreen")
		(1 "F.Mask" user)
		(3 "B.Mask" user)
		(17 "Dwgs.User" user "User.Drawings")
		(19 "Cmts.User" user "User.Comments")
		(21 "Eco1.User" user "User.Eco1")
		(23 "Eco2.User" user "User.Eco2")
		(25 "Edge.Cuts" user)
		(27 "Margin" user)
		(31 "F.CrtYd" user "F.Courtyard")
		(29 "B.CrtYd" user "B.Courtyard")
		(35 "F.Fab" user)
		(33 "B.Fab" user)
	)
	(footprint "antmicro-footprints:R_0402_1005Metric"
		(layer "F.Cu")
		(at 137.313 97.142 90)
		(descr "Resistor SMD 0402")
		(tags "resistor SMD 0402")
		(property "Reference" "R36"
			(at -1.41 -0.661 90)
			(layer "F.SilkS")
			(effects
				(font
					(size 0.7 0.7)
					(thickness 0.15)
				)
				(justify left bottom)
			)
		)
		(property "Value" "R_10k_0402"
			(at -1.011843 1.772047 90)
			(layer "F.Fab")
			(effects
				(font
					(size 0.7 0.7)
					(thickness 0.15)
				)
				(justify left bottom)
			)
		)
		(property "Datasheet" "https://www.bourns.com/docs/product-datasheets/cr.pdf"
			(at 0 0 90)
			(layer "F.Fab")
			(hide yes)
			(effects
				(font
					(size 1.27 1.27)
					(thickness 0.15)
				)
			)
		)
		(property "Description" "SMD Chip Resistor, 10 kohm, ± 1%, 62.5 mW, 0402 [1005 Metric], Thick Film, General Purpose"
			(at 0 0 90)
			(layer "F.Fab")
			(hide yes)
			(effects
				(font
					(size 1.27 1.27)
					(thickness 0.15)
				)
			)
		)
		(property "Author" "Antmicro"
			(at 234.455 -40.171 0)
			(layer "F.Fab")
			(hide yes)
			(effects
				(font
					(size 1 1)
					(thickness 0.15)
				)
			)
		)
		(property "License" "Apache-2.0"
			(at 234.455 -40.171 0)
			(layer "F.Fab")
			(hide yes)
			(effects
				(font
					(size 1 1)
					(thickness 0.15)
				)
			)
		)
		(property "MPN" "CR0402-FX-1002GLF"
			(at 234.455 -40.171 0)
			(layer "F.Fab")
			(hide yes)
			(effects
				(font
					(size 1 1)
					(thickness 0.15)
				)
			)
		)
		(property "Manufacturer" "Bourns"
			(at 234.455 -40.171 0)
			(layer "F.Fab")
			(hide yes)
			(effects
				(font
					(size 1 1)
					(thickness 0.15)
				)
			)
		)
		(property "Tolerance" "1%"
			(at 234.455 -40.171 0)
			(layer "F.Fab")
			(hide yes)
			(effects
				(font
					(size 1 1)
					(thickness 0.15)
				)
			)
		)
		(property "Val" "10k"
			(at 234.455 -40.171 0)
			(layer "F.Fab")
			(hide yes)
			(effects
				(font
					(size 1 1)
					(thickness 0.15)
				)
			)
		)
		(sheetname "/Power/")
		(sheetfile "power.kicad_sch")
		(attr smd)
		(fp_rect
			(start -0.925 -0.47)
			(end 0.925 0.47)
			(stroke
				(width 0.05)
				(type default)
			)
			(fill no)
			(layer "F.CrtYd")
		)
		(fp_rect
			(start -0.5 -0.25)
			(end 0.5 0.25)
			(stroke
				(width 0.15)
				(type solid)
			)
			(fill no)
			(layer "F.Fab")
		)
		(pad "1" smd roundrect
			(at -0.48 0 90)
			(size 0.59 0.64)
			(layers "F.Cu" "F.Mask" "F.Paste")
			(roundrect_rratio 0.25)
			(net 1 "GND")
			(pintype "passive")
		)
		(pad "2" smd roundrect
			(at 0.48 0 90)
			(size 0.59 0.64)
			(layers "F.Cu" "F.Mask" "F.Paste")
			(roundrect_rratio 0.25)
			(net 70 "/Power/FB_1V8")
			(pintype "passive")
		)
	)
	(footprint "antmicro-footprints:R_0402_1005Metric"
		(layer "F.Cu")
		(at 139.065 74.295 135)
		(descr "Resistor SMD 0402")
		(tags "resistor SMD 0402")
		(property "Reference" "R43"
			(at 6.164274 -0.378726 315)
			(unlocked yes)
			(layer "F.SilkS")
			(effects
				(font
					(size 0.7 0.7)
					(thickness 0.15)
				)
				(justify left bottom)
			)
		)
		(property "Value" "R_49R9_0402"
			(at -0.962843 2.788047 135)
			(layer "F.Fab")
			(effects
				(font
					(size 0.7 0.7)
					(thickness 0.15)
				)
				(justify left bottom)
			)
		)
		(property "Datasheet" "https://www.bourns.com/docs/product-datasheets/cr.pdf"
			(at 0 0 135)
			(layer "F.Fab")
			(hide yes)
			(effects
				(font
					(size 1.27 1.27)
					(thickness 0.15)
				)
			)
		)
		(property "Description" "SMD Chip Resistor, 49.9 ohm, ± 1%, 62.5 mW, 0402 [1005 Metric], Thick Film, General Purpose"
			(at 0 0 135)
			(layer "F.Fab")
			(hide yes)
			(effects
				(font
					(size 1.27 1.27)
					(thickness 0.15)
				)
			)
		)
		(property "Author" "Antmicro"
			(at 289.933303 28.495694 0)
			(layer "F.Fab")
			(hide yes)
			(effects
				(font
					(size 1 1)
					(thickness 0.15)
				)
			)
		)
		(property "License" "Apache-2.0"
			(at 289.933303 28.495694 0)
			(layer "F.Fab")
			(hide yes)
			(effects
				(font
					(size 1 1)
					(thickness 0.15)
				)
			)
		)
		(property "MPN" "CR0402-FX-49R9GLF"
			(at 289.933303 28.495694 0)
			(layer "F.Fab")
			(hide yes)
			(effects
				(font
					(size 1 1)
					(thickness 0.15)
				)
			)
		)
		(property "Manufacturer" "Bourns"
			(at 289.933303 28.495694 0)
			(layer "F.Fab")
			(hide yes)
			(effects
				(font
					(size 1 1)
					(thickness 0.15)
				)
			)
		)
		(property "Tolerance" "1%"
			(at 289.933303 28.495694 0)
			(layer "F.Fab")
			(hide yes)
			(effects
				(font
					(size 1 1)
					(thickness 0.15)
				)
			)
		)
		(property "Val" "49R9"
			(at 289.933303 28.495694 0)
			(layer "F.Fab")
			(hide yes)
			(effects
				(font
					(size 1 1)
					(thickness 0.15)
				)
			)
		)
		(sheetname "/Deserializer/")
		(sheetfile "deserializer.kicad_sch")
		(attr smd)
		(fp_poly
			(pts
				(xy -0.925 -0.47) (xy 0.925 -0.47) (xy 0.925 0.47) (xy -0.925 0.47)
			)
			(stroke
				(width 0.05)
				(type default)
			)
			(fill no)
			(layer "F.CrtYd")
		)
		(fp_poly
			(pts
				(xy -0.5 -0.25) (xy 0.5 -0.25) (xy 0.5 0.25) (xy -0.5 0.25)
			)
			(stroke
				(width 0.15)
				(type solid)
			)
			(fill no)
			(layer "F.Fab")
		)
		(pad "1" smd roundrect
			(at -0.48 0 135)
			(size 0.59 0.64)
			(layers "F.Cu" "F.Mask" "F.Paste")
			(roundrect_rratio 0.25)
			(net 19 "Net-(C32-Pad2)")
			(pintype "passive")
		)
		(pad "2" smd roundrect
			(at 0.48 0 135)
			(size 0.59 0.64)
			(layers "F.Cu" "F.Mask" "F.Paste")
			(roundrect_rratio 0.25)
			(net 1 "GND")
			(pintype "passive")
		)
	)
	(footprint "antmicro-footprints:L_0806_2016Metric"
		(layer "F.Cu")
		(at 123.88 87.226)
		(property "Reference" "L19"
			(at -1.524 2.032 0)
			(layer "F.SilkS")
			(effects
				(font
					(size 0.7 0.7)
					(thickness 0.15)
				)
				(justify left bottom)
			)
		)
		(property "Value" "L_1u_2.6A_0806"
			(at 0 2 0)
			(layer "F.Fab")
			(effects
				(font
					(size 0.7 0.7)
					(thickness 0.15)
				)
				(justify left bottom)
			)
		)
		(property "Datasheet" "https://www.bourns.com/docs/Product-Datasheets/SRP2010.pdf"
			(at 0 0 0)
			(layer "F.Fab")
			(hide yes)
			(effects
				(font
					(size 1.27 1.27)
					(thickness 0.15)
				)
			)
		)
		(property "Description" "Wirewound Inductor, 1 µH, 0.072 ohm, 2.6 A, SRP2010"
			(at 0 0 0)
			(layer "F.Fab")
			(hide yes)
			(effects
				(font
					(size 1.27 1.27)
					(thickness 0.15)
				)
			)
		)
		(property "Author" "Antmicro"
			(at 0 0 0)
			(layer "F.Fab")
			(hide yes)
			(effects
				(font
					(size 1 1)
					(thickness 0.15)
				)
			)
		)
		(property "IMax" "2.6 A"
			(at 0 0 0)
			(layer "F.Fab")
			(hide yes)
			(effects
				(font
					(size 1 1)
					(thickness 0.15)
				)
			)
		)
		(property "ISat" "2.9 A"
			(at 0 0 0)
			(layer "F.Fab")
			(hide yes)
			(effects
				(font
					(size 1 1)
					(thickness 0.15)
				)
			)
		)
		(property "License" "Apache-2.0"
			(at 0 0 0)
			(layer "F.Fab")
			(hide yes)
			(effects
				(font
					(size 1 1)
					(thickness 0.15)
				)
			)
		)
		(property "MPN" "SRP2010-1R0M"
			(at 0 0 0)
			(layer "F.Fab")
			(hide yes)
			(effects
				(font
					(size 1 1)
					(thickness 0.15)
				)
			)
		)
		(property "Manufacturer" "Bourns"
			(at 0 0 0)
			(layer "F.Fab")
			(hide yes)
			(effects
				(font
					(size 1 1)
					(thickness 0.15)
				)
			)
		)
		(property "Size" "2.0x1.6"
			(at 0 0 0)
			(layer "F.Fab")
			(hide yes)
			(effects
				(font
					(size 1 1)
					(thickness 0.15)
				)
			)
		)
		(property "Val" "1u/2.6A"
			(at 0 0 0)
			(layer "F.Fab")
			(hide yes)
			(effects
				(font
					(size 1 1)
					(thickness 0.15)
				)
			)
		)
		(sheetname "/Power/")
		(sheetfile "power.kicad_sch")
		(attr smd)
		(fp_line
			(start -0.301 0.9)
			(end 0.299 0.9)
			(stroke
				(width 0.15)
				(type solid)
			)
			(layer "F.SilkS")
		)
		(fp_line
			(start -0.3 -0.9)
			(end 0.298 -0.9)
			(stroke
				(width 0.15)
				(type solid)
			)
			(layer "F.SilkS")
		)
		(fp_rect
			(start -1.75 -1.05)
			(end 1.75 1.05)
			(stroke
				(width 0.05)
				(type solid)
			)
			(fill no)
			(layer "F.CrtYd")
		)
		(fp_rect
			(start -0.951 -0.882)
			(end 0.949 0.875)
			(stroke
				(width 0.15)
				(type solid)
			)
			(fill no)
			(layer "F.Fab")
		)
		(pad "1" smd roundrect
			(at -1.1 -0.001)
			(size 1 1.8)
			(layers "F.Cu" "F.Mask" "F.Paste")
			(roundrect_rratio 0.15)
			(net 9 "/Power/SW_1V2")
			(pintype "passive")
		)
		(pad "2" smd roundrect
			(at 1.1 -0.001)
			(size 1 1.8)
			(layers "F.Cu" "F.Mask" "F.Paste")
			(roundrect_rratio 0.15)
			(net 11 "/Power/OUT_1V2")
			(pintype "passive")
		)
	)
	(footprint "antmicro-footprints:LED_0603_1608Metric_G"
		(layer "F.Cu")
		(at 156.972 96.1 -90)
		(descr "LED SMD 0603 Green")
		(tags "LED SMD 0603 Green")
		(property "Reference" "D12"
			(at 0.994444 38.555333 0)
			(layer "F.SilkS")
			(effects
				(font
					(size 0.7 0.7)
					(thickness 0.15)
				)
				(justify right bottom)
			)
		)
		(property "Value" "LED_G_0603_LTST-C190GKT"
			(at -0.001 1.599 90)
			(layer "F.Fab")
			(effects
				(font
					(size 0.7 0.7)
					(thickness 0.15)
				)
				(justify right bottom)
			)
		)
		(property "Datasheet" "https://media.digikey.com/pdf/Data%20Sheets/Lite-On%20PDFs/LTST-C190GKT.pdf"
			(at 0 0 270)
			(layer "F.Fab")
			(hide yes)
			(effects
				(font
					(size 1.27 1.27)
					(thickness 0.15)
				)
			)
		)
		(property "Description" "LED, Green, SMD, 0603, 20 mA, 2.1 V, 569 nm"
			(at 0 0 270)
			(layer "F.Fab")
			(hide yes)
			(effects
				(font
					(size 1.27 1.27)
					(thickness 0.15)
				)
			)
		)
		(property "Author" "Antmicro"
			(at 60.872 253.072 0)
			(layer "F.Fab")
			(hide yes)
			(effects
				(font
					(size 1 1)
					(thickness 0.15)
				)
			)
		)
		(property "Color" "Green"
			(at 60.872 253.072 0)
			(layer "F.Fab")
			(hide yes)
			(effects
				(font
					(size 1 1)
					(thickness 0.15)
				)
			)
		)
		(property "License" "Apache-2.0"
			(at 60.872 253.072 0)
			(layer "F.Fab")
			(hide yes)
			(effects
				(font
					(size 1 1)
					(thickness 0.15)
				)
			)
		)
		(property "MPN" "LTST-C190GKT"
			(at 60.872 253.072 0)
			(layer "F.Fab")
			(hide yes)
			(effects
				(font
					(size 1 1)
					(thickness 0.15)
				)
			)
		)
		(property "Manufacturer" "Lite-On"
			(at 60.872 253.072 0)
			(layer "F.Fab")
			(hide yes)
			(effects
				(font
					(size 1 1)
					(thickness 0.15)
				)
			)
		)
		(property "VSD_class" "LED"
			(at 60.872 253.072 0)
			(layer "F.Fab")
			(hide yes)
			(effects
				(font
					(size 1 1)
					(thickness 0.15)
				)
			)
		)
		(sheetname "/Connectors/")
		(sheetfile "connectors.kicad_sch")
		(attr smd)
		(fp_line
			(start 0.22 0.35)
			(end -0.22 0.35)
			(stroke
				(width 0.15)
				(type solid)
			)
			(layer "F.SilkS")
		)
		(fp_line
			(start -0.094672 0.201008)
			(end -0.094672 -0.198992)
			(stroke
				(width 0.1)
				(type solid)
			)
			(layer "F.SilkS")
		)
		(fp_line
			(start 0.105328 0.201008)
			(end -0.094672 0.001008)
			(stroke
				(width 0.1)
				(type solid)
			)
			(layer "F.SilkS")
		)
		(fp_line
			(start 0.105328 0.201008)
			(end 0.105328 -0.198992)
			(stroke
				(width 0.1)
				(type solid)
			)
			(layer "F.SilkS")
		)
		(fp_line
			(start -0.094672 0.001008)
			(end -0.24 0.001008)
			(stroke
				(width 0.1)
				(type solid)
			)
			(layer "F.SilkS")
		)
		(fp_line
			(start -0.094672 0.001008)
			(end 0.105328 -0.198992)
			(stroke
				(width 0.1)
				(type solid)
			)
			(layer "F.SilkS")
		)
		(fp_line
			(start 0.105328 0.001008)
			(end 0.24 0.001)
			(stroke
				(width 0.1)
				(type solid)
			)
			(layer "F.SilkS")
		)
		(fp_line
			(start -1.18 -0.319)
			(end -1.18 0.321)
			(stroke
				(width 0.15)
				(type solid)
			)
			(layer "F.SilkS")
		)
		(fp_line
			(start 0.22 -0.35)
			(end -0.22 -0.35)
			(stroke
				(width 0.15)
				(type solid)
			)
			(layer "F.SilkS")
		)
		(fp_rect
			(start 1.25 0.65)
			(end -1.25 -0.65)
			(stroke
				(width 0.05)
				(type solid)
			)
			(fill no)
			(layer "F.CrtYd")
		)
		(fp_line
			(start -0.199 0.2)
			(end -0.199 0.1)
			(stroke
				(width 0.15)
				(type solid)
			)
			(layer "F.Fab")
		)
		(fp_line
			(start 0.201 0.2)
			(end 0.201 0)
			(stroke
				(width 0.15)
				(type solid)
			)
			(layer "F.Fab")
		)
		(fp_line
			(start -0.199 0)
			(end -0.597 0)
			(stroke
				(width 0.15)
				(type solid)
			)
			(layer "F.Fab")
		)
		(fp_line
			(start -0.101 0)
			(end 0.201 0.2)
			(stroke
				(width 0.15)
				(type solid)
			)
			(layer "F.Fab")
		)
		(fp_line
			(start 0.201 0)
			(end 0.201 -0.202)
			(stroke
				(width 0.15)
				(type solid)
			)
			(layer "F.Fab")
		)
		(fp_line
			(start 0.599 0)
			(end 0.201 0)
			(stroke
				(width 0.15)
				(type solid)
			)
			(layer "F.Fab")
		)
		(fp_line
			(start -0.199 -0.202)
			(end -0.199 0.1)
			(stroke
				(width 0.15)
				(type solid)
			)
			(layer "F.Fab")
		)
		(fp_line
			(start 0.201 -0.202)
			(end -0.101 0)
			(stroke
				(width 0.15)
				(type solid)
			)
			(layer "F.Fab")
		)
		(fp_rect
			(start 0.848 0.4)
			(end -0.85 -0.402)
			(stroke
				(width 0.15)
				(type solid)
			)
			(fill no)
			(layer "F.Fab")
		)
		(pad "1" smd roundrect
			(at -0.7 0 90)
			(size 0.8 1)
			(layers "F.Cu" "F.Mask" "F.Paste")
			(roundrect_rratio 0.2)
			(net 65 "Net-(D12-C)")
			(pinfunction "C")
			(pintype "passive")
		)
		(pad "2" smd roundrect
			(at 0.7 0 90)
			(size 0.8 1)
			(layers "F.Cu" "F.Mask" "F.Paste")
			(roundrect_rratio 0.2)
			(net 50 "/Connectors/FFC_3V3")
			(pinfunction "A")
			(pintype "passive")
		)
	)
	(footprint "antmicro-footprints:R_0402_1005Metric"
		(layer "F.Cu")
		(at 128.198 72.24 180)
		(descr "Resistor SMD 0402")
		(tags "resistor SMD 0402")
		(property "Reference" "R28"
			(at -1.016 0.739 0)
			(layer "F.SilkS")
			(effects
				(font
					(size 0.7 0.7)
					(thickness 0.15)
				)
				(justify right bottom)
			)
		)
		(property "Value" "R_0R_0402"
			(at -1.011843 1.772047 0)
			(layer "F.Fab")
			(effects
				(font
					(size 0.7 0.7)
					(thickness 0.15)
				)
				(justify right bottom)
			)
		)
		(property "Datasheet" "https://industrial.panasonic.com/cdbs/www-data/pdf/RDA0000/AOA0000C301.pdf"
			(at 0 0 180)
			(layer "F.Fab")
			(hide yes)
			(effects
				(font
					(size 1.27 1.27)
					(thickness 0.15)
				)
			)
		)
		(property "Description" "SMD Chip Resistor, Jumper, 0 ohm, 100 mW, 0402 [1005 Metric], Thick Film, General Purpose"
			(at 0 0 180)
			(layer "F.Fab")
			(hide yes)
			(effects
				(font
					(size 1.27 1.27)
					(thickness 0.15)
				)
			)
		)
		(property "Author" "Antmicro"
			(at 256.396 144.48 0)
			(layer "F.Fab")
			(hide yes)
			(effects
				(font
					(size 1 1)
					(thickness 0.15)
				)
			)
		)
		(property "Current" "1A"
			(at 256.396 144.48 0)
			(layer "F.Fab")
			(hide yes)
			(effects
				(font
					(size 1 1)
					(thickness 0.15)
				)
			)
		)
		(property "License" "Apache-2.0"
			(at 256.396 144.48 0)
			(layer "F.Fab")
			(hide yes)
			(effects
				(font
					(size 1 1)
					(thickness 0.15)
				)
			)
		)
		(property "MPN" "ERJ2GE0R00X"
			(at 256.396 144.48 0)
			(layer "F.Fab")
			(hide yes)
			(effects
				(font
					(size 1 1)
					(thickness 0.15)
				)
			)
		)
		(property "Manufacturer" "Panasonic"
			(at 256.396 144.48 0)
			(layer "F.Fab")
			(hide yes)
			(effects
				(font
					(size 1 1)
					(thickness 0.15)
				)
			)
		)
		(property "Tolerance" ""
			(at 256.396 144.48 0)
			(layer "F.Fab")
			(hide yes)
			(effects
				(font
					(size 1 1)
					(thickness 0.15)
				)
			)
		)
		(property "Val" "0R"
			(at 256.396 144.48 0)
			(layer "F.Fab")
			(hide yes)
			(effects
				(font
					(size 1 1)
					(thickness 0.15)
				)
			)
		)
		(sheetname "/Power/")
		(sheetfile "power.kicad_sch")
		(attr smd)
		(fp_rect
			(start -0.925 -0.47)
			(end 0.925 0.47)
			(stroke
				(width 0.05)
				(type default)
			)
			(fill no)
			(layer "F.CrtYd")
		)
		(fp_rect
			(start -0.5 -0.25)
			(end 0.5 0.25)
			(stroke
				(width 0.15)
				(type solid)
			)
			(fill no)
			(layer "F.Fab")
		)
		(pad "1" smd roundrect
			(at -0.48 0 180)
			(size 0.59 0.64)
			(layers "F.Cu" "F.Mask" "F.Paste")
			(roundrect_rratio 0.25)
			(net 125 "/Power/EN_12V")
			(pintype "passive")
		)
		(pad "2" smd roundrect
			(at 0.48 0 180)
			(size 0.59 0.64)
			(layers "F.Cu" "F.Mask" "F.Paste")
			(roundrect_rratio 0.25)
			(net 5 "+5V")
			(pintype "passive")
		)
	)
)
